(kicad_pcb
	(version 20260206)
	(generator "pcbnew")
	(generator_version "10.0")
	(general
		(thickness 1.6)
		(legacy_teardrops no)
	)
	(paper "A4")
	(title_block
		(title "Wiwynn_Tioga_Pass_MB.brd")
		(comment 1 "Tioga Pass / footprints 735-741 of 4770")
	)
	(layers
		(0 "F.Cu" signal "TOP")
		(4 "In1.Cu" signal "L2GND")
		(6 "In2.Cu" signal "L3")
		(8 "In3.Cu" signal "L4GND")
		(10 "In4.Cu" signal "L5")
		(12 "In5.Cu" signal "L6GND")
		(14 "In6.Cu" signal "L7VCC")
		(16 "In7.Cu" signal "L8VCC")
		(18 "In8.Cu" signal "L9GND")
		(20 "In9.Cu" signal "L10")
		(22 "In10.Cu" signal "L11GND")
		(24 "In11.Cu" signal "L12")
		(26 "In12.Cu" signal "L13GND")
		(2 "B.Cu" signal "BOTTOM")
		(9 "F.Adhes" user "F.Adhesive")
		(11 "B.Adhes" user "B.Adhesive")
		(13 "F.Paste" user "Package Geometry/Pastemask Top")
		(15 "B.Paste" user "Package Geometry/Pastemask Bottom")
		(5 "F.SilkS" user "Ref Des/Silkscreen Top")
		(7 "B.SilkS" user "Ref Des/Silkscreen Bottom")
		(1 "F.Mask" user "Board Geometry/Soldermask Top")
		(3 "B.Mask" user "Board Geometry/Soldermask Bottom")
		(17 "Dwgs.User" user "User.Drawings")
		(19 "Cmts.User" user "User.Comments")
		(21 "Eco1.User" user "User.Eco1")
		(23 "Eco2.User" user "User.Eco2")
		(25 "Edge.Cuts" user "Board Geometry/Outline")
		(27 "Margin" user)
		(31 "F.CrtYd" user "Package Geometry/Place Bound Top")
		(29 "B.CrtYd" user "Package Geometry/Place Bound Bottom")
		(35 "F.Fab" user "Ref Des/Assembly Top")
		(33 "B.Fab" user "Ref Des/Assembly Bottom")
	)
	(footprint ""
		(layer "F.Cu")
		(at 345.316048 -11.210036 180)
		(property "Reference" "CF16"
			(at 0 0 180)
			(layer "F.SilkS")
			(hide yes)
			(effects
				(font
					(size 1.27 1.27)
				)
			)
		)
		(property "Value" "*"
			(at 1.1811 -2.8194 180)
			(unlocked yes)
			(layer "F.Fab")
			(hide yes)
			(effects
				(font
					(size 1.27 1.016)
					(thickness 0.1524)
				)
			)
		)
		(property "Device Type" "SC22P50V2JN-4GP_SMD-BCG-SC22P5A"
			(at 1.1811 -4.3434 180)
			(unlocked yes)
			(layer "F.Fab")
			(hide yes)
			(effects
				(font
					(size 1.27 1.016)
					(thickness 0.1524)
				)
			)
		)
		(duplicate_pad_numbers_are_jumpers no)
		(fp_rect
			(start -0.4318 0.9525)
			(end 0.4318 -0.9525)
			(stroke
				(width 0)
				(type default)
			)
			(fill no)
			(layer "F.CrtYd")
		)
		(fp_rect
			(start -0.4318 0.9525)
			(end 0.4318 -0.9525)
			(stroke
				(width 0)
				(type default)
			)
			(fill no)
			(layer "F.Fab")
		)
		(pad "1" smd custom
			(at 0 -0.4445 180)
			(size 0.1524 0.1524)
			(layers "F.Cu" "F.Mask" "F.Paste")
			(net "VR_PVDDQ_ABC_AIREF2")
			(options
				(clearance outline)
				(anchor circle)
			)
			(primitives
				(gr_poly
					(pts
						(arc
							(start 0.3048 -0.2032)
							(mid 0.275042 -0.275042)
							(end 0.2032 -0.3048)
						)
						(arc
							(start -0.2032 -0.3048)
							(mid -0.275042 -0.275042)
							(end -0.3048 -0.2032)
						)
						(arc
							(start -0.3048 0.2032)
							(mid -0.275042 0.275042)
							(end -0.2032 0.3048)
						)
						(arc
							(start 0.2032 0.3048)
							(mid 0.275042 0.275042)
							(end 0.3048 0.2032)
						)
					)
					(width 0)
					(fill yes)
				)
			)
		)
		(pad "2" smd custom
			(at 0 0.4445 180)
			(size 0.1524 0.1524)
			(layers "F.Cu" "F.Mask" "F.Paste")
			(net "ISENSE_PVDDQ_ABC_PH2_IMON")
			(options
				(clearance outline)
				(anchor circle)
			)
			(primitives
				(gr_poly
					(pts
						(arc
							(start 0.3048 -0.2032)
							(mid 0.275042 -0.275042)
							(end 0.2032 -0.3048)
						)
						(arc
							(start -0.2032 -0.3048)
							(mid -0.275042 -0.275042)
							(end -0.3048 -0.2032)
						)
						(arc
							(start -0.3048 0.2032)
							(mid -0.275042 0.275042)
							(end -0.2032 0.3048)
						)
						(arc
							(start 0.2032 0.3048)
							(mid 0.275042 0.275042)
							(end 0.3048 0.2032)
						)
					)
					(width 0)
					(fill yes)
				)
			)
		)
	)
	(footprint ""
		(layer "F.Cu")
		(at 338.836 -20.5232 -90)
		(property "Reference" "R7F23"
			(at 0 0 270)
			(layer "F.SilkS")
			(hide yes)
			(effects
				(font
					(size 1.27 1.27)
				)
			)
		)
		(property "Value" ""
			(at 0 0 270)
			(layer "F.Fab")
			(effects
				(font
					(size 1.27 1.27)
				)
			)
		)
		(duplicate_pad_numbers_are_jumpers no)
		(fp_poly
			(pts
				(xy -0.2794 -0.1016) (xy 0.2794 -0.1016) (xy 0.2794 0.9906) (xy -0.2794 0.9906)
			)
			(stroke
				(width 0)
				(type default)
			)
			(fill no)
			(layer "F.CrtYd")
		)
		(fp_line
			(start -0.2794 0.9906)
			(end 0.2794 0.9906)
			(stroke
				(width 0.1)
				(type default)
			)
			(layer "F.Fab")
		)
		(fp_line
			(start 0.2794 0.9906)
			(end 0.2794 -0.1016)
			(stroke
				(width 0.1)
				(type default)
			)
			(layer "F.Fab")
		)
		(fp_line
			(start -0.2794 -0.1016)
			(end -0.2794 0.9906)
			(stroke
				(width 0.1)
				(type default)
			)
			(layer "F.Fab")
		)
		(fp_line
			(start 0.2794 -0.1016)
			(end -0.2794 -0.1016)
			(stroke
				(width 0.1)
				(type default)
			)
			(layer "F.Fab")
		)
		(pad "1" smd rect
			(at 0 0 270)
			(size 0.508 0.508)
			(layers "F.Cu" "F.Mask" "F.Paste")
			(net "IRQ_PVDDQ_ABC_VRHOT_LVT3_R_N")
		)
		(pad "2" smd rect
			(at 0 0.889 270)
			(size 0.508 0.508)
			(layers "F.Cu" "F.Mask" "F.Paste")
			(net "IRQ_PVDDQ_ABC_VRHOT_LVT3_N")
		)
		(zone
			(layer "F.Cu")
			(hatch none 0.5)
			(connect_pads
				(clearance 0)
			)
			(min_thickness 0.25)
			(keepout
				(tracks not_allowed)
				(vias allowed)
				(pads allowed)
				(copperpour not_allowed)
				(footprints allowed)
			)
			(placement
				(enabled no)
				(sheetname "")
			)
			(fill
				(thermal_gap 0.5)
				(thermal_bridge_width 0.5)
				(island_removal_mode 0)
			)
			(polygon
				(pts
					(xy 338.201 -20.7772) (xy 338.201 -20.2692) (xy 338.582 -20.2692) (xy 338.582 -20.7772)
				)
			)
		)
		(zone
			(layer "F.Cu")
			(hatch none 0.5)
			(connect_pads
				(clearance 0)
			)
			(min_thickness 0.25)
			(keepout
				(tracks allowed)
				(vias not_allowed)
				(pads allowed)
				(copperpour not_allowed)
				(footprints allowed)
			)
			(placement
				(enabled no)
				(sheetname "")
			)
			(fill
				(thermal_gap 0.5)
				(thermal_bridge_width 0.5)
				(island_removal_mode 0)
			)
			(polygon
				(pts
					(xy 338.582 -20.7772) (xy 338.582 -20.2692) (xy 338.201 -20.2692) (xy 338.201 -20.7772)
				)
			)
		)
	)
	(footprint ""
		(layer "F.Cu")
		(at 137.730484 12.014454 -90)
		(property "Reference" "T1P11"
			(at 0 0 270)
			(layer "F.SilkS")
			(hide yes)
			(effects
				(font
					(size 1.27 1.27)
				)
			)
		)
		(property "Value" "*"
			(at -3.302 1.12395 270)
			(unlocked yes)
			(layer "F.Fab")
			(hide yes)
			(effects
				(font
					(size 0.889 0.889)
					(thickness 0.1524)
				)
			)
		)
		(property "Device Type" "TPAD-DIFF-4P-GP_DISCRET-GB3-TPA"
			(at -3.302 -0.40005 270)
			(unlocked yes)
			(layer "F.Fab")
			(hide yes)
			(effects
				(font
					(size 0.889 0.889)
					(thickness 0.1524)
				)
			)
		)
		(duplicate_pad_numbers_are_jumpers no)
		(fp_line
			(start -2.286 2.286)
			(end 2.286 2.286)
			(stroke
				(width 0.1524)
				(type default)
			)
			(layer "F.SilkS")
		)
		(fp_line
			(start 2.286 2.286)
			(end 2.286 -2.286)
			(stroke
				(width 0.1524)
				(type default)
			)
			(layer "F.SilkS")
		)
		(fp_line
			(start -2.286 -2.286)
			(end -2.286 2.286)
			(stroke
				(width 0.1524)
				(type default)
			)
			(layer "F.SilkS")
		)
		(fp_line
			(start 2.286 -2.286)
			(end -2.286 -2.286)
			(stroke
				(width 0.1524)
				(type default)
			)
			(layer "F.SilkS")
		)
		(fp_line
			(start -2.413 -2.413)
			(end -2.413 -1.143)
			(stroke
				(width 0.4064)
				(type default)
			)
			(layer "F.SilkS")
		)
		(fp_line
			(start -1.143 -2.413)
			(end -2.413 -2.413)
			(stroke
				(width 0.4064)
				(type default)
			)
			(layer "F.SilkS")
		)
		(fp_rect
			(start -2.54 2.54)
			(end 2.54 -2.54)
			(stroke
				(width 0)
				(type default)
			)
			(fill no)
			(layer "F.CrtYd")
		)
		(fp_rect
			(start -2.54 2.54)
			(end 2.54 -2.54)
			(stroke
				(width 0)
				(type default)
			)
			(fill no)
			(layer "F.Fab")
		)
		(pad "1" thru_hole circle
			(at -1.27 -1.27 270)
			(size 1.524 1.524)
			(drill 0.9144)
			(layers "*.Cu" "*.Mask")
			(remove_unused_layers no)
			(net "L12_73OHM_6INCH_DP")
			(clearance -0.0508)
			(thermal_gap 0.127)
			(padstack
				(mode front_inner_back)
				(layer "Inner"
					(shape circle)
					(size 1.1684 1.1684)
					(clearance 0.127)
				)
				(layer "B.Cu"
					(shape circle)
					(size 1.524 1.524)
					(clearance -0.0508)
				)
			)
		)
		(pad "2" thru_hole circle
			(at 1.27 -1.27 270)
			(size 1.524 1.524)
			(drill 0.9144)
			(layers "*.Cu" "*.Mask")
			(remove_unused_layers no)
			(net "L12_73OHM_6INCH_DN")
			(clearance -0.0508)
			(thermal_gap 0.127)
			(padstack
				(mode front_inner_back)
				(layer "Inner"
					(shape circle)
					(size 1.1684 1.1684)
					(clearance 0.127)
				)
				(layer "B.Cu"
					(shape circle)
					(size 1.524 1.524)
					(clearance -0.0508)
				)
			)
		)
		(pad "GND1" thru_hole rect
			(at -1.27 1.27 270)
			(size 1.524 1.524)
			(drill 0.9144)
			(layers "*.Cu" "*.Mask")
			(remove_unused_layers no)
			(net "GND")
			(clearance -0.0508)
			(thermal_gap 0.127)
			(padstack
				(mode front_inner_back)
				(layer "Inner"
					(shape circle)
					(size 1.1684 1.1684)
					(clearance 0.127)
				)
				(layer "B.Cu"
					(shape rect)
					(size 1.524 1.524)
					(clearance -0.0508)
				)
			)
		)
		(pad "GND2" thru_hole rect
			(at 1.27 1.27 270)
			(size 1.524 1.524)
			(drill 0.9144)
			(layers "*.Cu" "*.Mask")
			(remove_unused_layers no)
			(net "GND")
			(clearance -0.0508)
			(thermal_gap 0.127)
			(padstack
				(mode front_inner_back)
				(layer "Inner"
					(shape circle)
					(size 1.1684 1.1684)
					(clearance 0.127)
				)
				(layer "B.Cu"
					(shape rect)
					(size 1.524 1.524)
					(clearance -0.0508)
				)
			)
		)
	)
	(footprint ""
		(layer "F.Cu")
		(at 174.244 -131.5085)
		(property "Reference" "R4B4"
			(at 0 0 0)
			(layer "F.SilkS")
			(hide yes)
			(effects
				(font
					(size 1.27 1.27)
				)
			)
		)
		(property "Value" ""
			(at 0 0 0)
			(layer "F.Fab")
			(effects
				(font
					(size 1.27 1.27)
				)
			)
		)
		(duplicate_pad_numbers_are_jumpers no)
		(fp_poly
			(pts
				(xy -0.2794 -0.1016) (xy 0.2794 -0.1016) (xy 0.2794 0.9906) (xy -0.2794 0.9906)
			)
			(stroke
				(width 0)
				(type default)
			)
			(fill no)
			(layer "F.CrtYd")
		)
		(fp_line
			(start -0.2794 -0.1016)
			(end -0.2794 0.9906)
			(stroke
				(width 0.1)
				(type default)
			)
			(layer "F.Fab")
		)
		(fp_line
			(start -0.2794 0.9906)
			(end 0.2794 0.9906)
			(stroke
				(width 0.1)
				(type default)
			)
			(layer "F.Fab")
		)
		(fp_line
			(start 0.2794 -0.1016)
			(end -0.2794 -0.1016)
			(stroke
				(width 0.1)
				(type default)
			)
			(layer "F.Fab")
		)
		(fp_line
			(start 0.2794 0.9906)
			(end 0.2794 -0.1016)
			(stroke
				(width 0.1)
				(type default)
			)
			(layer "F.Fab")
		)
		(pad "1" smd rect
			(at 0 0)
			(size 0.508 0.508)
			(layers "F.Cu" "F.Mask" "F.Paste")
			(net "VR_FB_PVPP_KLM")
		)
		(pad "2" smd rect
			(at 0 0.889)
			(size 0.508 0.508)
			(layers "F.Cu" "F.Mask" "F.Paste")
			(net "AGND_PVPP_KLM")
		)
		(zone
			(layer "F.Cu")
			(hatch none 0.5)
			(connect_pads
				(clearance 0)
			)
			(min_thickness 0.25)
			(keepout
				(tracks allowed)
				(vias not_allowed)
				(pads allowed)
				(copperpour not_allowed)
				(footprints allowed)
			)
			(placement
				(enabled no)
				(sheetname "")
			)
			(fill
				(thermal_gap 0.5)
				(thermal_bridge_width 0.5)
				(island_removal_mode 0)
			)
			(polygon
				(pts
					(xy 173.99 -131.2545) (xy 174.498 -131.2545) (xy 174.498 -130.8735) (xy 173.99 -130.8735)
				)
			)
		)
		(zone
			(layer "F.Cu")
			(hatch none 0.5)
			(connect_pads
				(clearance 0)
			)
			(min_thickness 0.25)
			(keepout
				(tracks not_allowed)
				(vias allowed)
				(pads allowed)
				(copperpour not_allowed)
				(footprints allowed)
			)
			(placement
				(enabled no)
				(sheetname "")
			)
			(fill
				(thermal_gap 0.5)
				(thermal_bridge_width 0.5)
				(island_removal_mode 0)
			)
			(polygon
				(pts
					(xy 173.99 -130.8735) (xy 174.498 -130.8735) (xy 174.498 -131.2545) (xy 173.99 -131.2545)
				)
			)
		)
	)
	(footprint ""
		(layer "F.Cu")
		(at 398.874996 -36.565586 90)
		(property "Reference" "R8G3"
			(at 0 0 90)
			(layer "F.SilkS")
			(hide yes)
			(effects
				(font
					(size 1.27 1.27)
				)
			)
		)
		(property "Value" ""
			(at 0 0 90)
			(layer "F.Fab")
			(effects
				(font
					(size 1.27 1.27)
				)
			)
		)
		(duplicate_pad_numbers_are_jumpers no)
		(fp_poly
			(pts
				(xy -0.2794 -0.1016) (xy 0.2794 -0.1016) (xy 0.2794 0.9906) (xy -0.2794 0.9906)
			)
			(stroke
				(width 0)
				(type default)
			)
			(fill no)
			(layer "F.CrtYd")
		)
		(fp_line
			(start 0.2794 -0.1016)
			(end -0.2794 -0.1016)
			(stroke
				(width 0.1)
				(type default)
			)
			(layer "F.Fab")
		)
		(fp_line
			(start -0.2794 -0.1016)
			(end -0.2794 0.9906)
			(stroke
				(width 0.1)
				(type default)
			)
			(layer "F.Fab")
		)
		(fp_line
			(start 0.2794 0.9906)
			(end 0.2794 -0.1016)
			(stroke
				(width 0.1)
				(type default)
			)
			(layer "F.Fab")
		)
		(fp_line
			(start -0.2794 0.9906)
			(end 0.2794 0.9906)
			(stroke
				(width 0.1)
				(type default)
			)
			(layer "F.Fab")
		)
		(pad "1" smd rect
			(at 0 0 90)
			(size 0.508 0.508)
			(layers "F.Cu" "F.Mask" "F.Paste")
			(net "P3V3_STBY")
		)
		(pad "2" smd rect
			(at 0 0.889 90)
			(size 0.508 0.508)
			(layers "F.Cu" "F.Mask" "F.Paste")
			(net "SMB_OCP_LAN_STBY_LVC3_SCL_R")
		)
		(zone
			(layer "F.Cu")
			(hatch none 0.5)
			(connect_pads
				(clearance 0)
			)
			(min_thickness 0.25)
			(keepout
				(tracks allowed)
				(vias not_allowed)
				(pads allowed)
				(copperpour not_allowed)
				(footprints allowed)
			)
			(placement
				(enabled no)
				(sheetname "")
			)
			(fill
				(thermal_gap 0.5)
				(thermal_bridge_width 0.5)
				(island_removal_mode 0)
			)
			(polygon
				(pts
					(xy 399.128996 -36.311586) (xy 399.128996 -36.819586) (xy 399.509996 -36.819586) (xy 399.509996 -36.311586)
				)
			)
		)
		(zone
			(layer "F.Cu")
			(hatch none 0.5)
			(connect_pads
				(clearance 0)
			)
			(min_thickness 0.25)
			(keepout
				(tracks not_allowed)
				(vias allowed)
				(pads allowed)
				(copperpour not_allowed)
				(footprints allowed)
			)
			(placement
				(enabled no)
				(sheetname "")
			)
			(fill
				(thermal_gap 0.5)
				(thermal_bridge_width 0.5)
				(island_removal_mode 0)
			)
			(polygon
				(pts
					(xy 399.509996 -36.311586) (xy 399.509996 -36.819586) (xy 399.128996 -36.819586) (xy 399.128996 -36.311586)
				)
			)
		)
	)
	(footprint ""
		(layer "F.Cu")
		(at 350.05518 -3.146552)
		(property "Reference" "C7G30"
			(at 0 0 0)
			(layer "F.SilkS")
			(hide yes)
			(effects
				(font
					(size 1.27 1.27)
				)
			)
		)
		(property "Value" ""
			(at 0 0 0)
			(layer "F.Fab")
			(effects
				(font
					(size 1.27 1.27)
				)
			)
		)
		(duplicate_pad_numbers_are_jumpers no)
		(fp_poly
			(pts
				(xy 0.3048 -0.1016) (xy 0.3048 0.9906) (xy -0.3048 0.9906) (xy -0.3048 -0.1016)
			)
			(stroke
				(width 0)
				(type default)
			)
			(fill no)
			(layer "F.CrtYd")
		)
		(fp_line
			(start -0.3048 -0.1016)
			(end -0.3048 0.9906)
			(stroke
				(width 0.1)
				(type default)
			)
			(layer "F.Fab")
		)
		(fp_line
			(start -0.3048 0.9906)
			(end 0.3048 0.9906)
			(stroke
				(width 0.1)
				(type default)
			)
			(layer "F.Fab")
		)
		(fp_line
			(start 0.3048 -0.1016)
			(end -0.3048 -0.1016)
			(stroke
				(width 0.1)
				(type default)
			)
			(layer "F.Fab")
		)
		(fp_line
			(start 0.3048 0.9906)
			(end 0.3048 -0.1016)
			(stroke
				(width 0.1)
				(type default)
			)
			(layer "F.Fab")
		)
		(pad "1" smd rect
			(at 0 0)
			(size 0.508 0.508)
			(layers "F.Cu" "F.Mask" "F.Paste")
			(net "VR_FET_SW_P12V_STBY_PVDDQ_ABC")
		)
		(pad "2" smd rect
			(at 0 0.889)
			(size 0.508 0.508)
			(layers "F.Cu" "F.Mask" "F.Paste")
			(net "GND")
		)
		(zone
			(layer "F.Cu")
			(hatch none 0.5)
			(connect_pads
				(clearance 0)
			)
			(min_thickness 0.25)
			(keepout
				(tracks allowed)
				(vias not_allowed)
				(pads allowed)
				(copperpour not_allowed)
				(footprints allowed)
			)
			(placement
				(enabled no)
				(sheetname "")
			)
			(fill
				(thermal_gap 0.5)
				(thermal_bridge_width 0.5)
				(island_removal_mode 0)
			)
			(polygon
				(pts
					(xy 349.80118 -2.892552) (xy 350.30918 -2.892552) (xy 350.30918 -2.511552) (xy 349.80118 -2.511552)
				)
			)
		)
		(zone
			(layer "F.Cu")
			(hatch none 0.5)
			(connect_pads
				(clearance 0)
			)
			(min_thickness 0.25)
			(keepout
				(tracks not_allowed)
				(vias allowed)
				(pads allowed)
				(copperpour not_allowed)
				(footprints allowed)
			)
			(placement
				(enabled no)
				(sheetname "")
			)
			(fill
				(thermal_gap 0.5)
				(thermal_bridge_width 0.5)
				(island_removal_mode 0)
			)
			(polygon
				(pts
					(xy 349.80118 -2.511552) (xy 350.30918 -2.511552) (xy 350.30918 -2.892552) (xy 349.80118 -2.892552)
				)
			)
		)
	)
	(footprint ""
		(layer "F.Cu")
		(at 318.543432 -12.954 -90)
		(property "Reference" "C6G1"
			(at 0 0 270)
			(layer "F.SilkS")
			(hide yes)
			(effects
				(font
					(size 1.27 1.27)
				)
			)
		)
		(property "Value" ""
			(at 0 0 270)
			(layer "F.Fab")
			(effects
				(font
					(size 1.27 1.27)
				)
			)
		)
		(duplicate_pad_numbers_are_jumpers no)
		(fp_poly
			(pts
				(xy -0.4953 -0.2032) (xy 0.4953 -0.2032) (xy 0.4953 1.6002) (xy -0.4953 1.6002)
			)
			(stroke
				(width 0)
				(type default)
			)
			(fill no)
			(layer "F.CrtYd")
		)
		(fp_line
			(start -0.4953 1.6002)
			(end -0.4953 -0.2032)
			(stroke
				(width 0.1)
				(type default)
			)
			(layer "F.Fab")
		)
		(fp_line
			(start 0.4953 1.6002)
			(end -0.4953 1.6002)
			(stroke
				(width 0.1)
				(type default)
			)
			(layer "F.Fab")
		)
		(fp_line
			(start -0.4953 -0.2032)
			(end 0.4953 -0.2032)
			(stroke
				(width 0.1)
				(type default)
			)
			(layer "F.Fab")
		)
		(fp_line
			(start 0.4953 -0.2032)
			(end 0.4953 1.6002)
			(stroke
				(width 0.1)
				(type default)
			)
			(layer "F.Fab")
		)
		(pad "1" smd rect
			(at 0 0 270)
			(size 0.762 0.889)
			(layers "F.Cu" "F.Mask" "F.Paste")
			(net "PVPP_ABC")
		)
		(pad "2" smd rect
			(at 0 1.397 270)
			(size 0.762 0.889)
			(layers "F.Cu" "F.Mask" "F.Paste")
			(net "GND")
		)
		(zone
			(layer "F.Cu")
			(hatch none 0.5)
			(connect_pads
				(clearance 0)
			)
			(min_thickness 0.25)
			(keepout
				(tracks not_allowed)
				(vias allowed)
				(pads allowed)
				(copperpour not_allowed)
				(footprints allowed)
			)
			(placement
				(enabled no)
				(sheetname "")
			)
			(fill
				(thermal_gap 0.5)
				(thermal_bridge_width 0.5)
				(island_removal_mode 0)
			)
			(polygon
				(pts
					(xy 318.098932 -13.335) (xy 318.098932 -12.573) (xy 317.590932 -12.573) (xy 317.590932 -13.335)
				)
			)
		)
	)
)
